(kicad_pcb
	(version 20260206)
	(generator "pcbnew")
	(generator_version "10.0")
	(general
		(thickness 1.6)
		(legacy_teardrops no)
	)
	(paper "A4")
	(title_block
		(title "03242023_DA0F0TMBIJ0_F0T_Motherboard_J_brd_V01_OCP.brd")
		(comment 1 "Grand Teton / footprints 1308-1314 of 6105")
	)
	(layers
		(0 "F.Cu" signal "TOP")
		(4 "In1.Cu" signal "GND")
		(6 "In2.Cu" signal "IN1")
		(8 "In3.Cu" signal "GND1")
		(10 "In4.Cu" signal "IN2")
		(12 "In5.Cu" signal "GND2")
		(14 "In6.Cu" signal "IN3")
		(16 "In7.Cu" signal "GND3")
		(18 "In8.Cu" signal "VCC")
		(20 "In9.Cu" signal "VCC1")
		(22 "In10.Cu" signal "GND4")
		(24 "In11.Cu" signal "IN4")
		(26 "In12.Cu" signal "GND5")
		(28 "In13.Cu" signal "IN5")
		(30 "In14.Cu" signal "GND6")
		(32 "In15.Cu" signal "IN6")
		(34 "In16.Cu" signal "GND7")
		(2 "B.Cu" signal "BOTTOM")
		(9 "F.Adhes" user "F.Adhesive")
		(11 "B.Adhes" user "B.Adhesive")
		(13 "F.Paste" user "Package Geometry/Pastemask Top")
		(15 "B.Paste" user "Package Geometry/Pastemask Bottom")
		(5 "F.SilkS" user "Ref Des/Silkscreen Top")
		(7 "B.SilkS" user "Ref Des/Silkscreen Bottom")
		(1 "F.Mask" user "Board Geometry/Soldermask Top")
		(3 "B.Mask" user "Board Geometry/Soldermask Bottom")
		(17 "Dwgs.User" user "User.Drawings")
		(19 "Cmts.User" user "User.Comments")
		(21 "Eco1.User" user "User.Eco1")
		(23 "Eco2.User" user "User.Eco2")
		(25 "Edge.Cuts" user "Board Geometry/Outline")
		(27 "Margin" user)
		(31 "F.CrtYd" user "Package Geometry/Place Bound Top")
		(29 "B.CrtYd" user "Package Geometry/Place Bound Bottom")
		(35 "F.Fab" user "Ref Des/Assembly Top")
		(33 "B.Fab" user "Ref Des/Assembly Bottom")
	)
	(footprint ""
		(layer "F.Cu")
		(at 180.528468 -50.060098 180)
		(property "Reference" "C1103"
			(at 0 0 180)
			(layer "F.SilkS")
			(hide yes)
			(effects
				(font
					(size 1.27 1.27)
				)
			)
		)
		(property "Value" ""
			(at 0 0 180)
			(layer "F.Fab")
			(effects
				(font
					(size 1.27 1.27)
				)
			)
		)
		(duplicate_pad_numbers_are_jumpers no)
		(fp_line
			(start 0.299974 0.150114)
			(end -0.299974 0.150114)
			(stroke
				(width 0.1)
				(type default)
			)
			(layer "F.Fab")
		)
		(fp_line
			(start 0.299974 -0.150114)
			(end 0.299974 0.150114)
			(stroke
				(width 0.1)
				(type default)
			)
			(layer "F.Fab")
		)
		(fp_line
			(start -0.299974 0.150114)
			(end -0.299974 -0.150114)
			(stroke
				(width 0.1)
				(type default)
			)
			(layer "F.Fab")
		)
		(fp_line
			(start -0.299974 -0.150114)
			(end 0.299974 -0.150114)
			(stroke
				(width 0.1)
				(type default)
			)
			(layer "F.Fab")
		)
		(pad "1" smd rect
			(at -0.2667 0 180)
			(size 0.3048 0.381)
			(layers "F.Cu" "F.Mask" "F.Paste")
			(net "P3E_PCH_M2_TX_DN<1>")
		)
		(pad "2" smd rect
			(at 0.2667 0 180)
			(size 0.3048 0.381)
			(layers "F.Cu" "F.Mask" "F.Paste")
			(net "P3E_PCH_M2_TX_C_DN<1>")
		)
		(zone
			(layer "In1.Cu")
			(hatch none 0.5)
			(connect_pads
				(clearance 0)
			)
			(min_thickness 0.25)
			(keepout
				(tracks not_allowed)
				(vias allowed)
				(pads allowed)
				(copperpour not_allowed)
				(footprints allowed)
			)
			(placement
				(enabled no)
				(sheetname "")
			)
			(fill
				(thermal_gap 0.5)
				(thermal_bridge_width 0.5)
				(island_removal_mode 0)
			)
			(polygon
				(pts
					(arc
						(start 180.388768 -50.301398)
						(mid 180.44265 -50.27908)
						(end 180.464968 -50.225198)
					)
					(arc
						(start 180.464968 -49.894998)
						(mid 180.44265 -49.841116)
						(end 180.388768 -49.818798)
					)
					(arc
						(start 180.134768 -49.818798)
						(mid 180.080886 -49.841116)
						(end 180.058568 -49.894998)
					)
					(arc
						(start 180.058568 -50.225198)
						(mid 180.080886 -50.27908)
						(end 180.134768 -50.301398)
					)
				)
			)
		)
		(zone
			(layer "In1.Cu")
			(hatch none 0.5)
			(connect_pads
				(clearance 0)
			)
			(min_thickness 0.25)
			(keepout
				(tracks not_allowed)
				(vias allowed)
				(pads allowed)
				(copperpour not_allowed)
				(footprints allowed)
			)
			(placement
				(enabled no)
				(sheetname "")
			)
			(fill
				(thermal_gap 0.5)
				(thermal_bridge_width 0.5)
				(island_removal_mode 0)
			)
			(polygon
				(pts
					(arc
						(start 180.922168 -50.301398)
						(mid 180.97605 -50.27908)
						(end 180.998368 -50.225198)
					)
					(arc
						(start 180.998368 -49.894998)
						(mid 180.97605 -49.841116)
						(end 180.922168 -49.818798)
					)
					(arc
						(start 180.668168 -49.818798)
						(mid 180.614286 -49.841116)
						(end 180.591968 -49.894998)
					)
					(arc
						(start 180.591968 -50.225198)
						(mid 180.614286 -50.27908)
						(end 180.668168 -50.301398)
					)
				)
			)
		)
	)
	(footprint ""
		(layer "F.Cu")
		(at 40.6146 -103.977948)
		(property "Reference" "R4568"
			(at 0 0 0)
			(layer "F.SilkS")
			(hide yes)
			(effects
				(font
					(size 1.27 1.27)
				)
			)
		)
		(property "Value" ""
			(at 0 0 0)
			(layer "F.Fab")
			(effects
				(font
					(size 1.27 1.27)
				)
			)
		)
		(duplicate_pad_numbers_are_jumpers no)
		(fp_line
			(start -0.7874 -0.4064)
			(end 0.7874 -0.4064)
			(stroke
				(width 0.1524)
				(type default)
			)
			(layer "F.SilkS")
		)
		(fp_line
			(start -0.7874 0.4064)
			(end -0.7874 -0.4064)
			(stroke
				(width 0.1524)
				(type default)
			)
			(layer "F.SilkS")
		)
		(fp_line
			(start 0.7874 -0.4064)
			(end 0.7874 0.4064)
			(stroke
				(width 0.1524)
				(type default)
			)
			(layer "F.SilkS")
		)
		(fp_line
			(start 0.7874 0.4064)
			(end -0.7874 0.4064)
			(stroke
				(width 0.1524)
				(type default)
			)
			(layer "F.SilkS")
		)
		(fp_line
			(start -0.67945 -0.305054)
			(end -0.12065 -0.305054)
			(stroke
				(width 0.1)
				(type default)
			)
			(layer "F.Fab")
		)
		(fp_line
			(start -0.67945 0.3048)
			(end -0.67945 -0.305054)
			(stroke
				(width 0.1)
				(type default)
			)
			(layer "F.Fab")
		)
		(fp_line
			(start -0.12065 -0.305054)
			(end -0.12065 -0.2794)
			(stroke
				(width 0.1)
				(type default)
			)
			(layer "F.Fab")
		)
		(fp_line
			(start -0.12065 -0.2794)
			(end 0.12065 -0.2794)
			(stroke
				(width 0.1)
				(type default)
			)
			(layer "F.Fab")
		)
		(fp_line
			(start -0.12065 0.2794)
			(end -0.12065 0.3048)
			(stroke
				(width 0.1)
				(type default)
			)
			(layer "F.Fab")
		)
		(fp_line
			(start -0.12065 0.3048)
			(end -0.67945 0.3048)
			(stroke
				(width 0.1)
				(type default)
			)
			(layer "F.Fab")
		)
		(fp_line
			(start 0.120396 0.2794)
			(end -0.12065 0.2794)
			(stroke
				(width 0.1)
				(type default)
			)
			(layer "F.Fab")
		)
		(fp_line
			(start 0.120396 0.3048)
			(end 0.120396 0.2794)
			(stroke
				(width 0.1)
				(type default)
			)
			(layer "F.Fab")
		)
		(fp_line
			(start 0.12065 -0.3048)
			(end 0.67945 -0.3048)
			(stroke
				(width 0.1)
				(type default)
			)
			(layer "F.Fab")
		)
		(fp_line
			(start 0.12065 -0.2794)
			(end 0.12065 -0.3048)
			(stroke
				(width 0.1)
				(type default)
			)
			(layer "F.Fab")
		)
		(fp_line
			(start 0.67945 -0.3048)
			(end 0.67945 0.3048)
			(stroke
				(width 0.1)
				(type default)
			)
			(layer "F.Fab")
		)
		(fp_line
			(start 0.67945 0.3048)
			(end 0.120396 0.3048)
			(stroke
				(width 0.1)
				(type default)
			)
			(layer "F.Fab")
		)
		(pad "1" smd circle
			(at -0.40005 0)
			(size 0 0)
			(layers "F.Cu" "F.Mask" "F.Paste")
			(net "P1V581_PDB_ADC")
		)
		(pad "2" smd circle
			(at 0.40005 0)
			(size 0 0)
			(layers "F.Cu" "F.Mask" "F.Paste")
			(net "GND")
		)
	)
	(footprint ""
		(layer "F.Cu")
		(at 498.89918 -467.976966)
		(property "Reference" "DM13"
			(at -0.3937 -0.588518 0)
			(unlocked yes)
			(layer "F.SilkS")
			(effects
				(font
					(size 0.254 0.127)
					(thickness 0.000001)
				)
				(justify left)
			)
		)
		(property "Value" ""
			(at 0 0 0)
			(layer "F.Fab")
			(effects
				(font
					(size 1.27 1.27)
				)
			)
		)
		(duplicate_pad_numbers_are_jumpers no)
		(pad "1" smd circle
			(at 0 0)
			(size 0.762 0.762)
			(layers "F.Cu" "F.Mask" "F.Paste")
			(net "Net_8588")
		)
	)
	(footprint ""
		(layer "F.Cu")
		(at 356.945184 -337.830668)
		(property "Reference" "PC296_P0_2"
			(at 0 0 0)
			(layer "F.SilkS")
			(hide yes)
			(effects
				(font
					(size 1.27 1.27)
				)
			)
		)
		(property "Value" ""
			(at 0 0 0)
			(layer "F.Fab")
			(effects
				(font
					(size 1.27 1.27)
				)
			)
		)
		(duplicate_pad_numbers_are_jumpers no)
		(fp_line
			(start -0.7874 -0.4064)
			(end 0.7874 -0.4064)
			(stroke
				(width 0.1524)
				(type default)
			)
			(layer "F.SilkS")
		)
		(fp_line
			(start -0.7874 0.4064)
			(end -0.7874 -0.4064)
			(stroke
				(width 0.1524)
				(type default)
			)
			(layer "F.SilkS")
		)
		(fp_line
			(start 0.7874 -0.4064)
			(end 0.7874 0.4064)
			(stroke
				(width 0.1524)
				(type default)
			)
			(layer "F.SilkS")
		)
		(fp_line
			(start 0.7874 0.4064)
			(end -0.7874 0.4064)
			(stroke
				(width 0.1524)
				(type default)
			)
			(layer "F.SilkS")
		)
		(fp_line
			(start -0.67945 -0.305054)
			(end -0.12065 -0.305054)
			(stroke
				(width 0.1)
				(type default)
			)
			(layer "F.Fab")
		)
		(fp_line
			(start -0.67945 0.3048)
			(end -0.67945 -0.305054)
			(stroke
				(width 0.1)
				(type default)
			)
			(layer "F.Fab")
		)
		(fp_line
			(start -0.12065 -0.305054)
			(end -0.12065 -0.2794)
			(stroke
				(width 0.1)
				(type default)
			)
			(layer "F.Fab")
		)
		(fp_line
			(start -0.12065 -0.2794)
			(end 0.12065 -0.2794)
			(stroke
				(width 0.1)
				(type default)
			)
			(layer "F.Fab")
		)
		(fp_line
			(start -0.12065 0.2794)
			(end -0.12065 0.3048)
			(stroke
				(width 0.1)
				(type default)
			)
			(layer "F.Fab")
		)
		(fp_line
			(start -0.12065 0.3048)
			(end -0.67945 0.3048)
			(stroke
				(width 0.1)
				(type default)
			)
			(layer "F.Fab")
		)
		(fp_line
			(start 0.120396 0.2794)
			(end -0.12065 0.2794)
			(stroke
				(width 0.1)
				(type default)
			)
			(layer "F.Fab")
		)
		(fp_line
			(start 0.120396 0.3048)
			(end 0.120396 0.2794)
			(stroke
				(width 0.1)
				(type default)
			)
			(layer "F.Fab")
		)
		(fp_line
			(start 0.12065 -0.3048)
			(end 0.67945 -0.3048)
			(stroke
				(width 0.1)
				(type default)
			)
			(layer "F.Fab")
		)
		(fp_line
			(start 0.12065 -0.2794)
			(end 0.12065 -0.3048)
			(stroke
				(width 0.1)
				(type default)
			)
			(layer "F.Fab")
		)
		(fp_line
			(start 0.67945 -0.3048)
			(end 0.67945 0.3048)
			(stroke
				(width 0.1)
				(type default)
			)
			(layer "F.Fab")
		)
		(fp_line
			(start 0.67945 0.3048)
			(end 0.120396 0.3048)
			(stroke
				(width 0.1)
				(type default)
			)
			(layer "F.Fab")
		)
		(pad "1" smd circle
			(at -0.40005 0)
			(size 0 0)
			(layers "F.Cu" "F.Mask" "F.Paste")
			(net "SW_P12V_PVCCIN_CPU0_FLT")
		)
		(pad "2" smd circle
			(at 0.40005 0)
			(size 0 0)
			(layers "F.Cu" "F.Mask" "F.Paste")
			(net "GND")
		)
	)
	(footprint ""
		(layer "F.Cu")
		(at 352.287078 -238.162338 -90)
		(property "Reference" "C417"
			(at 0 0 270)
			(layer "F.SilkS")
			(hide yes)
			(effects
				(font
					(size 1.27 1.27)
				)
			)
		)
		(property "Value" ""
			(at 0 0 270)
			(layer "F.Fab")
			(effects
				(font
					(size 1.27 1.27)
				)
			)
		)
		(duplicate_pad_numbers_are_jumpers no)
		(fp_line
			(start -0.7874 0.4064)
			(end -0.7874 -0.4064)
			(stroke
				(width 0.1524)
				(type default)
			)
			(layer "F.SilkS")
		)
		(fp_line
			(start 0.7874 0.4064)
			(end -0.7874 0.4064)
			(stroke
				(width 0.1524)
				(type default)
			)
			(layer "F.SilkS")
		)
		(fp_line
			(start -0.7874 -0.4064)
			(end 0.7874 -0.4064)
			(stroke
				(width 0.1524)
				(type default)
			)
			(layer "F.SilkS")
		)
		(fp_line
			(start 0.7874 -0.4064)
			(end 0.7874 0.4064)
			(stroke
				(width 0.1524)
				(type default)
			)
			(layer "F.SilkS")
		)
		(fp_line
			(start -0.67945 0.3048)
			(end -0.67945 -0.305054)
			(stroke
				(width 0.1)
				(type default)
			)
			(layer "F.Fab")
		)
		(fp_line
			(start -0.12065 0.3048)
			(end -0.67945 0.3048)
			(stroke
				(width 0.1)
				(type default)
			)
			(layer "F.Fab")
		)
		(fp_line
			(start 0.120396 0.3048)
			(end 0.120396 0.2794)
			(stroke
				(width 0.1)
				(type default)
			)
			(layer "F.Fab")
		)
		(fp_line
			(start 0.67945 0.3048)
			(end 0.120396 0.3048)
			(stroke
				(width 0.1)
				(type default)
			)
			(layer "F.Fab")
		)
		(fp_line
			(start -0.12065 0.2794)
			(end -0.12065 0.3048)
			(stroke
				(width 0.1)
				(type default)
			)
			(layer "F.Fab")
		)
		(fp_line
			(start 0.120396 0.2794)
			(end -0.12065 0.2794)
			(stroke
				(width 0.1)
				(type default)
			)
			(layer "F.Fab")
		)
		(fp_line
			(start -0.12065 -0.2794)
			(end 0.12065 -0.2794)
			(stroke
				(width 0.1)
				(type default)
			)
			(layer "F.Fab")
		)
		(fp_line
			(start 0.12065 -0.2794)
			(end 0.12065 -0.3048)
			(stroke
				(width 0.1)
				(type default)
			)
			(layer "F.Fab")
		)
		(fp_line
			(start 0.12065 -0.3048)
			(end 0.67945 -0.3048)
			(stroke
				(width 0.1)
				(type default)
			)
			(layer "F.Fab")
		)
		(fp_line
			(start 0.67945 -0.3048)
			(end 0.67945 0.3048)
			(stroke
				(width 0.1)
				(type default)
			)
			(layer "F.Fab")
		)
		(fp_line
			(start -0.67945 -0.305054)
			(end -0.12065 -0.305054)
			(stroke
				(width 0.1)
				(type default)
			)
			(layer "F.Fab")
		)
		(fp_line
			(start -0.12065 -0.305054)
			(end -0.12065 -0.2794)
			(stroke
				(width 0.1)
				(type default)
			)
			(layer "F.Fab")
		)
		(pad "1" smd circle
			(at -0.40005 0 270)
			(size 0 0)
			(layers "F.Cu" "F.Mask" "F.Paste")
			(net "PVCCFA_EHV_FIVRA_CPU0")
		)
		(pad "2" smd circle
			(at 0.40005 0 270)
			(size 0 0)
			(layers "F.Cu" "F.Mask" "F.Paste")
			(net "GND")
		)
	)
	(footprint ""
		(layer "F.Cu")
		(at 109.14888 -54.574948)
		(property "Reference" "R3026"
			(at 0 0 0)
			(layer "F.SilkS")
			(hide yes)
			(effects
				(font
					(size 1.27 1.27)
				)
			)
		)
		(property "Value" ""
			(at 0 0 0)
			(layer "F.Fab")
			(effects
				(font
					(size 1.27 1.27)
				)
			)
		)
		(duplicate_pad_numbers_are_jumpers no)
		(fp_line
			(start -0.7874 -0.4064)
			(end 0.7874 -0.4064)
			(stroke
				(width 0.1524)
				(type default)
			)
			(layer "F.SilkS")
		)
		(fp_line
			(start -0.7874 0.4064)
			(end -0.7874 -0.4064)
			(stroke
				(width 0.1524)
				(type default)
			)
			(layer "F.SilkS")
		)
		(fp_line
			(start 0.7874 -0.4064)
			(end 0.7874 0.4064)
			(stroke
				(width 0.1524)
				(type default)
			)
			(layer "F.SilkS")
		)
		(fp_line
			(start 0.7874 0.4064)
			(end -0.7874 0.4064)
			(stroke
				(width 0.1524)
				(type default)
			)
			(layer "F.SilkS")
		)
		(fp_line
			(start -0.67945 -0.305054)
			(end -0.12065 -0.305054)
			(stroke
				(width 0.1)
				(type default)
			)
			(layer "F.Fab")
		)
		(fp_line
			(start -0.67945 0.3048)
			(end -0.67945 -0.305054)
			(stroke
				(width 0.1)
				(type default)
			)
			(layer "F.Fab")
		)
		(fp_line
			(start -0.12065 -0.305054)
			(end -0.12065 -0.2794)
			(stroke
				(width 0.1)
				(type default)
			)
			(layer "F.Fab")
		)
		(fp_line
			(start -0.12065 -0.2794)
			(end 0.12065 -0.2794)
			(stroke
				(width 0.1)
				(type default)
			)
			(layer "F.Fab")
		)
		(fp_line
			(start -0.12065 0.2794)
			(end -0.12065 0.3048)
			(stroke
				(width 0.1)
				(type default)
			)
			(layer "F.Fab")
		)
		(fp_line
			(start -0.12065 0.3048)
			(end -0.67945 0.3048)
			(stroke
				(width 0.1)
				(type default)
			)
			(layer "F.Fab")
		)
		(fp_line
			(start 0.120396 0.2794)
			(end -0.12065 0.2794)
			(stroke
				(width 0.1)
				(type default)
			)
			(layer "F.Fab")
		)
		(fp_line
			(start 0.120396 0.3048)
			(end 0.120396 0.2794)
			(stroke
				(width 0.1)
				(type default)
			)
			(layer "F.Fab")
		)
		(fp_line
			(start 0.12065 -0.3048)
			(end 0.67945 -0.3048)
			(stroke
				(width 0.1)
				(type default)
			)
			(layer "F.Fab")
		)
		(fp_line
			(start 0.12065 -0.2794)
			(end 0.12065 -0.3048)
			(stroke
				(width 0.1)
				(type default)
			)
			(layer "F.Fab")
		)
		(fp_line
			(start 0.67945 -0.3048)
			(end 0.67945 0.3048)
			(stroke
				(width 0.1)
				(type default)
			)
			(layer "F.Fab")
		)
		(fp_line
			(start 0.67945 0.3048)
			(end 0.120396 0.3048)
			(stroke
				(width 0.1)
				(type default)
			)
			(layer "F.Fab")
		)
		(pad "1" smd circle
			(at -0.40005 0)
			(size 0 0)
			(layers "F.Cu" "F.Mask" "F.Paste")
			(net "JTAG_BMC_PCH_TCK")
		)
		(pad "2" smd circle
			(at 0.40005 0)
			(size 0 0)
			(layers "F.Cu" "F.Mask" "F.Paste")
			(net "GND")
		)
	)
	(footprint ""
		(layer "F.Cu")
		(at 325.61276 -22.675088 90)
		(property "Reference" "R1207"
			(at 0 0 90)
			(layer "F.SilkS")
			(hide yes)
			(effects
				(font
					(size 1.27 1.27)
				)
			)
		)
		(property "Value" ""
			(at 0 0 90)
			(layer "F.Fab")
			(effects
				(font
					(size 1.27 1.27)
				)
			)
		)
		(duplicate_pad_numbers_are_jumpers no)
		(fp_line
			(start 0.7874 -0.4064)
			(end 0.7874 0.4064)
			(stroke
				(width 0.1524)
				(type default)
			)
			(layer "F.SilkS")
		)
		(fp_line
			(start -0.7874 -0.4064)
			(end 0.7874 -0.4064)
			(stroke
				(width 0.1524)
				(type default)
			)
			(layer "F.SilkS")
		)
		(fp_line
			(start 0.7874 0.4064)
			(end -0.7874 0.4064)
			(stroke
				(width 0.1524)
				(type default)
			)
			(layer "F.SilkS")
		)
		(fp_line
			(start -0.7874 0.4064)
			(end -0.7874 -0.4064)
			(stroke
				(width 0.1524)
				(type default)
			)
			(layer "F.SilkS")
		)
		(fp_line
			(start -0.12065 -0.305054)
			(end -0.12065 -0.2794)
			(stroke
				(width 0.1)
				(type default)
			)
			(layer "F.Fab")
		)
		(fp_line
			(start -0.67945 -0.305054)
			(end -0.12065 -0.305054)
			(stroke
				(width 0.1)
				(type default)
			)
			(layer "F.Fab")
		)
		(fp_line
			(start 0.67945 -0.3048)
			(end 0.67945 0.3048)
			(stroke
				(width 0.1)
				(type default)
			)
			(layer "F.Fab")
		)
		(fp_line
			(start 0.12065 -0.3048)
			(end 0.67945 -0.3048)
			(stroke
				(width 0.1)
				(type default)
			)
			(layer "F.Fab")
		)
		(fp_line
			(start 0.12065 -0.2794)
			(end 0.12065 -0.3048)
			(stroke
				(width 0.1)
				(type default)
			)
			(layer "F.Fab")
		)
		(fp_line
			(start -0.12065 -0.2794)
			(end 0.12065 -0.2794)
			(stroke
				(width 0.1)
				(type default)
			)
			(layer "F.Fab")
		)
		(fp_line
			(start 0.120396 0.2794)
			(end -0.12065 0.2794)
			(stroke
				(width 0.1)
				(type default)
			)
			(layer "F.Fab")
		)
		(fp_line
			(start -0.12065 0.2794)
			(end -0.12065 0.3048)
			(stroke
				(width 0.1)
				(type default)
			)
			(layer "F.Fab")
		)
		(fp_line
			(start 0.67945 0.3048)
			(end 0.120396 0.3048)
			(stroke
				(width 0.1)
				(type default)
			)
			(layer "F.Fab")
		)
		(fp_line
			(start 0.120396 0.3048)
			(end 0.120396 0.2794)
			(stroke
				(width 0.1)
				(type default)
			)
			(layer "F.Fab")
		)
		(fp_line
			(start -0.12065 0.3048)
			(end -0.67945 0.3048)
			(stroke
				(width 0.1)
				(type default)
			)
			(layer "F.Fab")
		)
		(fp_line
			(start -0.67945 0.3048)
			(end -0.67945 -0.305054)
			(stroke
				(width 0.1)
				(type default)
			)
			(layer "F.Fab")
		)
		(pad "1" smd circle
			(at -0.40005 0 90)
			(size 0 0)
			(layers "F.Cu" "F.Mask" "F.Paste")
			(net "RST_RSMRST_PLD_R_N")
		)
		(pad "2" smd circle
			(at 0.40005 0 90)
			(size 0 0)
			(layers "F.Cu" "F.Mask" "F.Paste")
			(net "RST_RSMRST_PCH_N")
		)
	)
)
